# Data Center RDIMM DDR4 Tester — KiCad custom design rules (.kicad_dru)
(version 1)

(rule "PCIe_85Ohm_in2" 
	(constraint track_width (opt 0.13mm))
	(constraint clearance (opt 0.1mm))
	(constraint diff_pair_gap  (opt 0.176mm))
	(condition "(A.NetClass == '85Ohm-diff_PCIe')&& !A.insideCourtyard('U15')")
	(layer "In2.Cu")
)

(rule "PCIe_85Ohm_in2_BGA" 
	(constraint track_width (opt 0.082mm))
	(constraint clearance (opt 0.1mm))
	(constraint diff_pair_gap  (opt 0.09mm))
	(condition "(A.NetClass == '85Ohm-diff_PCIe') && A.insideCourtyard('U15')")
	(layer "In2.Cu")
)

(rule "PCIe_85Ohm_in9" 
	(constraint track_width (opt 0.13mm))
	(constraint clearance (opt 0.1mm))
	(constraint diff_pair_gap  (opt 0.176mm))
	(condition "(A.NetClass == '85Ohm-diff_PCIe')&& !A.insideCourtyard('U15')")
	(layer "In9.Cu")
)

(rule "PCIe_85Ohm_in9_BGA" 
	(constraint track_width (opt 0.082mm))
	(constraint clearance (opt 0.1mm))
	(constraint diff_pair_gap  (opt 0.09mm))
	(condition "(A.NetClass == '85Ohm-diff_PCIe') && A.insideCourtyard('U15')")
	(layer "In9.Cu")
)

(rule "PCIe_85Ohm_in5" 
	(constraint track_width (opt 0.105mm))
	(constraint clearance (opt 0.1mm))
	(constraint diff_pair_gap  (opt 0.23mm))
	(condition "(A.NetClass == '85Ohm-diff_PCIe')&& !A.insideCourtyard('U15')")
	(layer "In5.Cu")
)

(rule "PCIe_85Ohm_in5_BGA" 
	(constraint track_width (opt 0.08mm))
	(constraint clearance (opt 0.1mm))
	(constraint diff_pair_gap  (opt 0.1mm))
	(condition "(A.NetClass == '85Ohm-diff_PCIe') && A.insideCourtyard('U15')")
	(layer "In5.Cu")
)

(rule "PCIe_85Ohm_outer_BGA" 
# calculated as 85Ohm @ 50 Ohm SE
	(constraint track_width (opt 0.1mm) )
	(constraint diff_pair_gap (opt 0.09mm))
	(constraint clearance (opt 0.1mm))
	(condition "(A.NetClass == '85Ohm-diff_PCIe')&& A.insideCourtyard('U15')")
	(layer outer)
)

(rule "PCIe_85Ohm_outer" 
# calculated as 85Ohm @ 45 Ohm SE
	(constraint track_width (opt 0.122mm) )
	(constraint diff_pair_gap (opt 0.165mm))
	(constraint clearance (opt 0.1mm))
	(condition "(A.NetClass == '85Ohm-diff_PCIe')&& !A.insideCourtyard('U15')")
	(layer outer)
)

(rule "DDR_80OHM_diff_outer" 
	(constraint track_width (opt 0.1mm))
	(constraint diff_pair_gap (opt 0.2mm))
	(constraint clearance (opt 0.1mm))
	(condition "(A.NetClass == '80Ohm-diff_DQS') ")
	(layer outer)
)

(rule "DDR_40OHM_SE_outer" 
	(constraint track_width (opt 0.2mm))
	(constraint clearance (opt 0.1mm))
	(condition "(A.NetClass == '40Ohm-se_DQ')")
	(layer outer)
)

(rule "DDR_50OHM_SE_BGA_L5" 
	(constraint track_width (opt 0.09mm))
	(constraint clearance (opt 0.1mm))
	(condition "(A.NetClass == '40Ohm-se_DQ') && A.insideCourtyard('U15')")
	(layer "In5.Cu")
)

(rule "DDR_100OHM_diff_BGA_L5" 
# calculated as 95Ohm @ 50 Ohm SE
	(constraint track_width (opt 0.09mm))
	(constraint diff_pair_gap (opt 0.2mm))
	(constraint clearance (opt 0.1mm))
	(condition "(A.NetClass == '80Ohm-diff_DQS') && A.insideCourtyard('U15')")
	(layer "In5.Cu")
)

(rule "DDR_40OHM_SE_L5" 
	(constraint track_width (opt 0.146mm))
	(constraint clearance (min 0.1mm) (opt 0.4mm))
	(condition "(A.NetClass == '40Ohm-se_DQ') && !A.insideCourtyard('U15')")
	(layer "In5.Cu")
)

(rule "DDR_80OHM_diff_L5" 
# calculated as 80Ohm @43 Ohm SE
	(constraint track_width (opt 0.127mm))
	(constraint diff_pair_gap (opt 0.16mm))
	(constraint clearance (opt 0.1mm))
	(condition "(A.NetClass == '80Ohm-diff_DQS') && !A.insideCourtyard('U15')")
	(layer "In5.Cu")
)

(rule "DDR_50OHM_SE_BGA_L2" 
	(constraint track_width (opt 0.1mm))
	(constraint clearance (opt 0.1mm))
	(condition "(A.NetClass == '40Ohm-se_DQ') && A.insideCourtyard('U15')")
	(layer "In2.Cu")
)

(rule "DDR_100OHM_diff_BGA_L2" 
# calculated as 95Ohm @ 50 Ohm SE
	(constraint track_width (opt 0.1mm))
	(constraint diff_pair_gap (opt 0.17mm))
	(constraint clearance (opt 0.1mm))
	(condition "(A.NetClass == '80Ohm-diff_DQS') && A.insideCourtyard('U15')")
	(layer "In2.Cu")
)

(rule "DDR_40OHM_SE_L2" 
	(constraint track_width (opt 0.16mm))
	(constraint clearance (min 0.1mm) (opt 0.4mm))
	(condition "(A.NetClass == '40Ohm-se_DQ') && !A.insideCourtyard('U15')")
	(layer "In2.Cu")
)

(rule "DDR_80OHM_diff_L2" 
# calculated as 80Ohm @43 Ohm SE
	(constraint track_width (opt 0.143mm))
	(constraint diff_pair_gap (opt 0.158mm))
	(constraint clearance (opt 0.1mm))
	(condition "(A.NetClass == '80Ohm-diff_DQS') && !A.insideCourtyard('U15')")
	(layer "In2.Cu")
)

(rule "DDR_50OHM_SE_BGA_L9" 
	(constraint track_width (opt 0.1mm))
	(constraint clearance (opt 0.1mm))
	(condition "(A.NetClass == '40Ohm-se_DQ') && A.insideCourtyard('U15')")
	(layer "In9.Cu")
)

(rule "DDR_100OHM_diff_BGA_L9" 
# calculated as 95Ohm @ 50 Ohm SE
	(constraint track_width (opt 0.1mm))
	(constraint diff_pair_gap (opt 0.17mm))
	(constraint clearance (opt 0.1mm))
	(condition "(A.NetClass == '80Ohm-diff_DQS') && A.insideCourtyard('U15')")
	(layer "In9.Cu")
)

(rule "DDR_40OHM_SE_L9" 
	(constraint track_width (opt 0.16mm))
	(constraint clearance (min 0.1mm) (opt 0.4mm))
	(condition "(A.NetClass == '40Ohm-se_DQ') && !A.insideCourtyard('U15')")
	(layer "In9.Cu")
)

(rule "DDR_80OHM_diff_L9" 
# calculated as 80Ohm @43 Ohm SE
	(constraint track_width (opt 0.143mm))
	(constraint diff_pair_gap (opt 0.158mm))
	(constraint clearance (opt 0.1mm))
	(condition "(A.NetClass == '40Ohm-diff_DQS') && !A.insideCourtyard('U15')")
	(layer "In9.Cu")
)

(rule "DDR_50OHM_SE_BGA_L7" 
	(constraint track_width (opt 0.127mm))
	(constraint clearance (opt 0.1mm))
	(condition "(A.NetClass == '40Ohm-se_DQ') && A.insideCourtyard('U15')")
	(layer "In7.Cu")
)

(rule "DDR_100OHM_diff_BGA_L7" 
# calculated as 95Ohm @ 51 Ohm SE
	(constraint track_width (opt 0.09mm))
	(constraint diff_pair_gap (opt 0.2mm))
	(constraint clearance (opt 0.1mm))
	(condition "(A.NetClass == '80Ohm-diff_DQS') && A.insideCourtyard('U15')")
	(layer "In7.Cu")
)

(rule "DDR_40OHM_SE_L7" 
	(constraint track_width (opt 0.196mm))
	(constraint clearance (min 0.1mm) (opt 0.4mm))
	(condition "(A.NetClass == '40Ohm-se_DQ') && !A.insideCourtyard('U15')")
	(layer "In7.Cu")
)

(rule "DDR_80OHM_diff_L7" 
# calculated as 80Ohm @42,5 Ohm SE
	(constraint track_width (opt 0.166mm))
	(constraint diff_pair_gap (opt 0.225mm))
	(constraint clearance (opt 0.1mm))
	(condition "(A.NetClass == '80Ohm-diff_DQS') && !A.insideCourtyard('U15')")
	(layer "In7.Cu")
)

(rule "FMC_90OHM_diff_inner_BGA" 
# calculated as 90Ohm @53 Ohm SE
	(constraint track_width (opt 0.09mm))
	(constraint diff_pair_gap (opt 0.11mm))
	(constraint clearance (opt 0.1mm))
	(condition "(A.NetClass == '90Ohm-diff_FMC') && A.insideCourtyard('U15')")
	(layer inner)
)
